(kicad_pcb
	(version 20260206)
	(generator "pcbnew")
	(generator_version "10.0")
	(general
		(thickness 1.6)
		(legacy_teardrops no)
	)
	(paper "A4")
	(title_block
		(title "03242023_DA0F0TMBIJ0_F0T_Motherboard_J_brd_V01_OCP.brd")
		(comment 1 "Grand Teton / footprints 1509-1515 of 6105")
	)
	(layers
		(0 "F.Cu" signal "TOP")
		(4 "In1.Cu" signal "GND")
		(6 "In2.Cu" signal "IN1")
		(8 "In3.Cu" signal "GND1")
		(10 "In4.Cu" signal "IN2")
		(12 "In5.Cu" signal "GND2")
		(14 "In6.Cu" signal "IN3")
		(16 "In7.Cu" signal "GND3")
		(18 "In8.Cu" signal "VCC")
		(20 "In9.Cu" signal "VCC1")
		(22 "In10.Cu" signal "GND4")
		(24 "In11.Cu" signal "IN4")
		(26 "In12.Cu" signal "GND5")
		(28 "In13.Cu" signal "IN5")
		(30 "In14.Cu" signal "GND6")
		(32 "In15.Cu" signal "IN6")
		(34 "In16.Cu" signal "GND7")
		(2 "B.Cu" signal "BOTTOM")
		(9 "F.Adhes" user "F.Adhesive")
		(11 "B.Adhes" user "B.Adhesive")
		(13 "F.Paste" user "Package Geometry/Pastemask Top")
		(15 "B.Paste" user "Package Geometry/Pastemask Bottom")
		(5 "F.SilkS" user "Ref Des/Silkscreen Top")
		(7 "B.SilkS" user "Ref Des/Silkscreen Bottom")
		(1 "F.Mask" user "Board Geometry/Soldermask Top")
		(3 "B.Mask" user "Board Geometry/Soldermask Bottom")
		(17 "Dwgs.User" user "User.Drawings")
		(19 "Cmts.User" user "User.Comments")
		(21 "Eco1.User" user "User.Eco1")
		(23 "Eco2.User" user "User.Eco2")
		(25 "Edge.Cuts" user "Board Geometry/Outline")
		(27 "Margin" user)
		(31 "F.CrtYd" user "Package Geometry/Place Bound Top")
		(29 "B.CrtYd" user "Package Geometry/Place Bound Bottom")
		(35 "F.Fab" user "Ref Des/Assembly Top")
		(33 "B.Fab" user "Ref Des/Assembly Bottom")
	)
	(footprint ""
		(layer "F.Cu")
		(at 240.854484 -56.527192 180)
		(property "Reference" "C1991"
			(at 0 0 180)
			(layer "F.SilkS")
			(hide yes)
			(effects
				(font
					(size 1.27 1.27)
				)
			)
		)
		(property "Value" ""
			(at 0 0 180)
			(layer "F.Fab")
			(effects
				(font
					(size 1.27 1.27)
				)
			)
		)
		(duplicate_pad_numbers_are_jumpers no)
		(fp_line
			(start 0.299974 0.150114)
			(end -0.299974 0.150114)
			(stroke
				(width 0.1)
				(type default)
			)
			(layer "F.Fab")
		)
		(fp_line
			(start 0.299974 -0.150114)
			(end 0.299974 0.150114)
			(stroke
				(width 0.1)
				(type default)
			)
			(layer "F.Fab")
		)
		(fp_line
			(start -0.299974 0.150114)
			(end -0.299974 -0.150114)
			(stroke
				(width 0.1)
				(type default)
			)
			(layer "F.Fab")
		)
		(fp_line
			(start -0.299974 -0.150114)
			(end 0.299974 -0.150114)
			(stroke
				(width 0.1)
				(type default)
			)
			(layer "F.Fab")
		)
		(pad "1" smd rect
			(at -0.2667 0 180)
			(size 0.3048 0.381)
			(layers "F.Cu" "F.Mask" "F.Paste")
			(net "P3E_PCH_E1S_TX_DP<2>")
		)
		(pad "2" smd rect
			(at 0.2667 0 180)
			(size 0.3048 0.381)
			(layers "F.Cu" "F.Mask" "F.Paste")
			(net "P3E_PCH_E1S_TX_C_DP<2>")
		)
		(zone
			(layer "In1.Cu")
			(hatch none 0.5)
			(connect_pads
				(clearance 0)
			)
			(min_thickness 0.25)
			(keepout
				(tracks not_allowed)
				(vias allowed)
				(pads allowed)
				(copperpour not_allowed)
				(footprints allowed)
			)
			(placement
				(enabled no)
				(sheetname "")
			)
			(fill
				(thermal_gap 0.5)
				(thermal_bridge_width 0.5)
				(island_removal_mode 0)
			)
			(polygon
				(pts
					(arc
						(start 240.714784 -56.767476)
						(mid 240.768666 -56.745158)
						(end 240.790984 -56.691276)
					)
					(arc
						(start 240.790984 -56.361076)
						(mid 240.768666 -56.307194)
						(end 240.714784 -56.284876)
					)
					(arc
						(start 240.460784 -56.284876)
						(mid 240.406902 -56.307194)
						(end 240.384584 -56.361076)
					)
					(arc
						(start 240.384584 -56.691276)
						(mid 240.406902 -56.745158)
						(end 240.460784 -56.767476)
					)
				)
			)
		)
		(zone
			(layer "In1.Cu")
			(hatch none 0.5)
			(connect_pads
				(clearance 0)
			)
			(min_thickness 0.25)
			(keepout
				(tracks not_allowed)
				(vias allowed)
				(pads allowed)
				(copperpour not_allowed)
				(footprints allowed)
			)
			(placement
				(enabled no)
				(sheetname "")
			)
			(fill
				(thermal_gap 0.5)
				(thermal_bridge_width 0.5)
				(island_removal_mode 0)
			)
			(polygon
				(pts
					(arc
						(start 241.248184 -56.767476)
						(mid 241.302066 -56.745158)
						(end 241.324384 -56.691276)
					)
					(arc
						(start 241.324384 -56.361076)
						(mid 241.302066 -56.307194)
						(end 241.248184 -56.284876)
					)
					(arc
						(start 240.994184 -56.284876)
						(mid 240.940302 -56.307194)
						(end 240.917984 -56.361076)
					)
					(arc
						(start 240.917984 -56.691276)
						(mid 240.940302 -56.745158)
						(end 240.994184 -56.767476)
					)
				)
			)
		)
	)
	(footprint ""
		(layer "F.Cu")
		(at 93.295724 -65.223644 -90)
		(property "Reference" "R3068"
			(at 0 0 270)
			(layer "F.SilkS")
			(hide yes)
			(effects
				(font
					(size 1.27 1.27)
				)
			)
		)
		(property "Value" ""
			(at 0 0 270)
			(layer "F.Fab")
			(effects
				(font
					(size 1.27 1.27)
				)
			)
		)
		(duplicate_pad_numbers_are_jumpers no)
		(fp_line
			(start -0.7874 0.4064)
			(end -0.7874 -0.4064)
			(stroke
				(width 0.1524)
				(type default)
			)
			(layer "F.SilkS")
		)
		(fp_line
			(start 0.7874 0.4064)
			(end -0.7874 0.4064)
			(stroke
				(width 0.1524)
				(type default)
			)
			(layer "F.SilkS")
		)
		(fp_line
			(start -0.7874 -0.4064)
			(end 0.7874 -0.4064)
			(stroke
				(width 0.1524)
				(type default)
			)
			(layer "F.SilkS")
		)
		(fp_line
			(start 0.7874 -0.4064)
			(end 0.7874 0.4064)
			(stroke
				(width 0.1524)
				(type default)
			)
			(layer "F.SilkS")
		)
		(fp_line
			(start -0.67945 0.3048)
			(end -0.67945 -0.305054)
			(stroke
				(width 0.1)
				(type default)
			)
			(layer "F.Fab")
		)
		(fp_line
			(start -0.12065 0.3048)
			(end -0.67945 0.3048)
			(stroke
				(width 0.1)
				(type default)
			)
			(layer "F.Fab")
		)
		(fp_line
			(start 0.120396 0.3048)
			(end 0.120396 0.2794)
			(stroke
				(width 0.1)
				(type default)
			)
			(layer "F.Fab")
		)
		(fp_line
			(start 0.67945 0.3048)
			(end 0.120396 0.3048)
			(stroke
				(width 0.1)
				(type default)
			)
			(layer "F.Fab")
		)
		(fp_line
			(start -0.12065 0.2794)
			(end -0.12065 0.3048)
			(stroke
				(width 0.1)
				(type default)
			)
			(layer "F.Fab")
		)
		(fp_line
			(start 0.120396 0.2794)
			(end -0.12065 0.2794)
			(stroke
				(width 0.1)
				(type default)
			)
			(layer "F.Fab")
		)
		(fp_line
			(start -0.12065 -0.2794)
			(end 0.12065 -0.2794)
			(stroke
				(width 0.1)
				(type default)
			)
			(layer "F.Fab")
		)
		(fp_line
			(start 0.12065 -0.2794)
			(end 0.12065 -0.3048)
			(stroke
				(width 0.1)
				(type default)
			)
			(layer "F.Fab")
		)
		(fp_line
			(start 0.12065 -0.3048)
			(end 0.67945 -0.3048)
			(stroke
				(width 0.1)
				(type default)
			)
			(layer "F.Fab")
		)
		(fp_line
			(start 0.67945 -0.3048)
			(end 0.67945 0.3048)
			(stroke
				(width 0.1)
				(type default)
			)
			(layer "F.Fab")
		)
		(fp_line
			(start -0.67945 -0.305054)
			(end -0.12065 -0.305054)
			(stroke
				(width 0.1)
				(type default)
			)
			(layer "F.Fab")
		)
		(fp_line
			(start -0.12065 -0.305054)
			(end -0.12065 -0.2794)
			(stroke
				(width 0.1)
				(type default)
			)
			(layer "F.Fab")
		)
		(pad "1" smd circle
			(at -0.40005 0 270)
			(size 0 0)
			(layers "F.Cu" "F.Mask" "F.Paste")
			(net "LED_PWRGD_PCH_PWROK_R")
		)
		(pad "2" smd circle
			(at 0.40005 0 270)
			(size 0 0)
			(layers "F.Cu" "F.Mask" "F.Paste")
			(net "P3V3_AUX")
		)
	)
	(footprint ""
		(layer "F.Cu")
		(at 404.006812 -55.759604)
		(property "Reference" "C552"
			(at 0 0 0)
			(layer "F.SilkS")
			(hide yes)
			(effects
				(font
					(size 1.27 1.27)
				)
			)
		)
		(property "Value" ""
			(at 0 0 0)
			(layer "F.Fab")
			(effects
				(font
					(size 1.27 1.27)
				)
			)
		)
		(duplicate_pad_numbers_are_jumpers no)
		(fp_line
			(start -0.7874 -0.4064)
			(end 0.7874 -0.4064)
			(stroke
				(width 0.1524)
				(type default)
			)
			(layer "F.SilkS")
		)
		(fp_line
			(start -0.7874 0.4064)
			(end -0.7874 -0.4064)
			(stroke
				(width 0.1524)
				(type default)
			)
			(layer "F.SilkS")
		)
		(fp_line
			(start 0.7874 -0.4064)
			(end 0.7874 0.4064)
			(stroke
				(width 0.1524)
				(type default)
			)
			(layer "F.SilkS")
		)
		(fp_line
			(start 0.7874 0.4064)
			(end -0.7874 0.4064)
			(stroke
				(width 0.1524)
				(type default)
			)
			(layer "F.SilkS")
		)
		(fp_line
			(start -0.67945 -0.305054)
			(end -0.12065 -0.305054)
			(stroke
				(width 0.1)
				(type default)
			)
			(layer "F.Fab")
		)
		(fp_line
			(start -0.67945 0.3048)
			(end -0.67945 -0.305054)
			(stroke
				(width 0.1)
				(type default)
			)
			(layer "F.Fab")
		)
		(fp_line
			(start -0.12065 -0.305054)
			(end -0.12065 -0.2794)
			(stroke
				(width 0.1)
				(type default)
			)
			(layer "F.Fab")
		)
		(fp_line
			(start -0.12065 -0.2794)
			(end 0.12065 -0.2794)
			(stroke
				(width 0.1)
				(type default)
			)
			(layer "F.Fab")
		)
		(fp_line
			(start -0.12065 0.2794)
			(end -0.12065 0.3048)
			(stroke
				(width 0.1)
				(type default)
			)
			(layer "F.Fab")
		)
		(fp_line
			(start -0.12065 0.3048)
			(end -0.67945 0.3048)
			(stroke
				(width 0.1)
				(type default)
			)
			(layer "F.Fab")
		)
		(fp_line
			(start 0.120396 0.2794)
			(end -0.12065 0.2794)
			(stroke
				(width 0.1)
				(type default)
			)
			(layer "F.Fab")
		)
		(fp_line
			(start 0.120396 0.3048)
			(end 0.120396 0.2794)
			(stroke
				(width 0.1)
				(type default)
			)
			(layer "F.Fab")
		)
		(fp_line
			(start 0.12065 -0.3048)
			(end 0.67945 -0.3048)
			(stroke
				(width 0.1)
				(type default)
			)
			(layer "F.Fab")
		)
		(fp_line
			(start 0.12065 -0.2794)
			(end 0.12065 -0.3048)
			(stroke
				(width 0.1)
				(type default)
			)
			(layer "F.Fab")
		)
		(fp_line
			(start 0.67945 -0.3048)
			(end 0.67945 0.3048)
			(stroke
				(width 0.1)
				(type default)
			)
			(layer "F.Fab")
		)
		(fp_line
			(start 0.67945 0.3048)
			(end 0.120396 0.3048)
			(stroke
				(width 0.1)
				(type default)
			)
			(layer "F.Fab")
		)
		(pad "1" smd circle
			(at -0.40005 0)
			(size 0 0)
			(layers "F.Cu" "F.Mask" "F.Paste")
			(net "FM_CPU_FBRK_DEBUG_N")
		)
		(pad "2" smd circle
			(at 0.40005 0)
			(size 0 0)
			(layers "F.Cu" "F.Mask" "F.Paste")
			(net "GND")
		)
	)
	(footprint ""
		(layer "F.Cu")
		(at 341.651082 -24.217122 -90)
		(property "Reference" "R727"
			(at 0 0 270)
			(layer "F.SilkS")
			(hide yes)
			(effects
				(font
					(size 1.27 1.27)
				)
			)
		)
		(property "Value" ""
			(at 0 0 270)
			(layer "F.Fab")
			(effects
				(font
					(size 1.27 1.27)
				)
			)
		)
		(duplicate_pad_numbers_are_jumpers no)
		(fp_line
			(start -0.7874 0.4064)
			(end -0.7874 -0.4064)
			(stroke
				(width 0.1524)
				(type default)
			)
			(layer "F.SilkS")
		)
		(fp_line
			(start 0.7874 0.4064)
			(end -0.7874 0.4064)
			(stroke
				(width 0.1524)
				(type default)
			)
			(layer "F.SilkS")
		)
		(fp_line
			(start -0.7874 -0.4064)
			(end 0.7874 -0.4064)
			(stroke
				(width 0.1524)
				(type default)
			)
			(layer "F.SilkS")
		)
		(fp_line
			(start 0.7874 -0.4064)
			(end 0.7874 0.4064)
			(stroke
				(width 0.1524)
				(type default)
			)
			(layer "F.SilkS")
		)
		(fp_line
			(start -0.67945 0.3048)
			(end -0.67945 -0.305054)
			(stroke
				(width 0.1)
				(type default)
			)
			(layer "F.Fab")
		)
		(fp_line
			(start -0.12065 0.3048)
			(end -0.67945 0.3048)
			(stroke
				(width 0.1)
				(type default)
			)
			(layer "F.Fab")
		)
		(fp_line
			(start 0.120396 0.3048)
			(end 0.120396 0.2794)
			(stroke
				(width 0.1)
				(type default)
			)
			(layer "F.Fab")
		)
		(fp_line
			(start 0.67945 0.3048)
			(end 0.120396 0.3048)
			(stroke
				(width 0.1)
				(type default)
			)
			(layer "F.Fab")
		)
		(fp_line
			(start -0.12065 0.2794)
			(end -0.12065 0.3048)
			(stroke
				(width 0.1)
				(type default)
			)
			(layer "F.Fab")
		)
		(fp_line
			(start 0.120396 0.2794)
			(end -0.12065 0.2794)
			(stroke
				(width 0.1)
				(type default)
			)
			(layer "F.Fab")
		)
		(fp_line
			(start -0.12065 -0.2794)
			(end 0.12065 -0.2794)
			(stroke
				(width 0.1)
				(type default)
			)
			(layer "F.Fab")
		)
		(fp_line
			(start 0.12065 -0.2794)
			(end 0.12065 -0.3048)
			(stroke
				(width 0.1)
				(type default)
			)
			(layer "F.Fab")
		)
		(fp_line
			(start 0.12065 -0.3048)
			(end 0.67945 -0.3048)
			(stroke
				(width 0.1)
				(type default)
			)
			(layer "F.Fab")
		)
		(fp_line
			(start 0.67945 -0.3048)
			(end 0.67945 0.3048)
			(stroke
				(width 0.1)
				(type default)
			)
			(layer "F.Fab")
		)
		(fp_line
			(start -0.67945 -0.305054)
			(end -0.12065 -0.305054)
			(stroke
				(width 0.1)
				(type default)
			)
			(layer "F.Fab")
		)
		(fp_line
			(start -0.12065 -0.305054)
			(end -0.12065 -0.2794)
			(stroke
				(width 0.1)
				(type default)
			)
			(layer "F.Fab")
		)
		(pad "1" smd circle
			(at -0.40005 0 270)
			(size 0 0)
			(layers "F.Cu" "F.Mask" "F.Paste")
			(net "PU_OC4_USB_N")
		)
		(pad "2" smd circle
			(at 0.40005 0 270)
			(size 0 0)
			(layers "F.Cu" "F.Mask" "F.Paste")
			(net "P3V3_AUX")
		)
	)
	(footprint ""
		(layer "F.Cu")
		(at 90.582496 -70.78599)
		(property "Reference" "D88"
			(at -46.009306 50.178462 90)
			(unlocked yes)
			(layer "F.SilkS")
			(effects
				(font
					(size 0.635 0.4064)
					(thickness 0.1524)
				)
				(justify left)
			)
		)
		(property "Value" ""
			(at 0 0 0)
			(layer "F.Fab")
			(effects
				(font
					(size 1.27 1.27)
				)
			)
		)
		(duplicate_pad_numbers_are_jumpers no)
		(fp_line
			(start -0.90678 0.4826)
			(end -0.90678 -0.4699)
			(stroke
				(width 0.1524)
				(type default)
			)
			(layer "F.SilkS")
		)
		(fp_line
			(start -0.89408 -0.4826)
			(end 0.90678 -0.4826)
			(stroke
				(width 0.1524)
				(type default)
			)
			(layer "F.SilkS")
		)
		(fp_line
			(start -0.79248 -0.4826)
			(end 1.03378 -0.4826)
			(stroke
				(width 0.1524)
				(type default)
			)
			(layer "F.SilkS")
		)
		(fp_line
			(start -0.64008 -0.4826)
			(end 1.16078 -0.4826)
			(stroke
				(width 0.1524)
				(type default)
			)
			(layer "F.SilkS")
		)
		(fp_line
			(start 0.90678 -0.4826)
			(end 0.90678 0.4826)
			(stroke
				(width 0.1524)
				(type default)
			)
			(layer "F.SilkS")
		)
		(fp_line
			(start 0.90678 0.4826)
			(end -0.90678 0.4826)
			(stroke
				(width 0.1524)
				(type default)
			)
			(layer "F.SilkS")
		)
		(fp_line
			(start 1.03378 -0.4826)
			(end 1.03378 0.4826)
			(stroke
				(width 0.1524)
				(type default)
			)
			(layer "F.SilkS")
		)
		(fp_line
			(start 1.03378 0.4826)
			(end -0.79248 0.4826)
			(stroke
				(width 0.1524)
				(type default)
			)
			(layer "F.SilkS")
		)
		(fp_line
			(start 1.16078 -0.4826)
			(end 1.16078 0.4826)
			(stroke
				(width 0.1524)
				(type default)
			)
			(layer "F.SilkS")
		)
		(fp_line
			(start 1.16078 0.4826)
			(end -0.64008 0.4826)
			(stroke
				(width 0.1524)
				(type default)
			)
			(layer "F.SilkS")
		)
		(fp_line
			(start -0.499872 -0.249936)
			(end 0.499872 -0.249936)
			(stroke
				(width 0.1)
				(type default)
			)
			(layer "F.Fab")
		)
		(fp_line
			(start -0.499872 0.249936)
			(end -0.499872 -0.249936)
			(stroke
				(width 0.1)
				(type default)
			)
			(layer "F.Fab")
		)
		(fp_line
			(start 0.499872 -0.249936)
			(end 0.499872 0.249936)
			(stroke
				(width 0.1)
				(type default)
			)
			(layer "F.Fab")
		)
		(fp_line
			(start 0.499872 0.249936)
			(end -0.499872 0.249936)
			(stroke
				(width 0.1)
				(type default)
			)
			(layer "F.Fab")
		)
		(pad "A" smd rect
			(at -0.47498 0)
			(size 0.6096 0.7112)
			(layers "F.Cu" "F.Mask" "F.Paste")
			(net "LED_PWRGD_SYS_PWROK_R")
		)
		(pad "C" smd rect
			(at 0.47498 0)
			(size 0.6096 0.7112)
			(layers "F.Cu" "F.Mask" "F.Paste")
			(net "LED_PWRGD_SYS_PWROK_R_D")
		)
	)
	(footprint ""
		(layer "F.Cu")
		(at 427.592236 -17.612614 90)
		(property "Reference" "C865"
			(at 0 0 90)
			(layer "F.SilkS")
			(hide yes)
			(effects
				(font
					(size 1.27 1.27)
				)
			)
		)
		(property "Value" ""
			(at 0 0 90)
			(layer "F.Fab")
			(effects
				(font
					(size 1.27 1.27)
				)
			)
		)
		(duplicate_pad_numbers_are_jumpers no)
		(fp_line
			(start 0.299974 -0.150114)
			(end 0.299974 0.150114)
			(stroke
				(width 0.1)
				(type default)
			)
			(layer "F.Fab")
		)
		(fp_line
			(start -0.299974 -0.150114)
			(end 0.299974 -0.150114)
			(stroke
				(width 0.1)
				(type default)
			)
			(layer "F.Fab")
		)
		(fp_line
			(start 0.299974 0.150114)
			(end -0.299974 0.150114)
			(stroke
				(width 0.1)
				(type default)
			)
			(layer "F.Fab")
		)
		(fp_line
			(start -0.299974 0.150114)
			(end -0.299974 -0.150114)
			(stroke
				(width 0.1)
				(type default)
			)
			(layer "F.Fab")
		)
		(pad "1" smd rect
			(at -0.2667 0 90)
			(size 0.3048 0.381)
			(layers "F.Cu" "F.Mask" "F.Paste")
			(net "P5E_CPU0_PE1_TX_C_DP<2>")
		)
		(pad "2" smd rect
			(at 0.2667 0 90)
			(size 0.3048 0.381)
			(layers "F.Cu" "F.Mask" "F.Paste")
			(net "P5E_CPU0_PE1_TX_DP<2>")
		)
	)
	(footprint ""
		(layer "F.Cu")
		(at 110.079282 -406.058116 90)
		(property "Reference" "R3495"
			(at 0 0 90)
			(layer "F.SilkS")
			(hide yes)
			(effects
				(font
					(size 1.27 1.27)
				)
			)
		)
		(property "Value" ""
			(at 0 0 90)
			(layer "F.Fab")
			(effects
				(font
					(size 1.27 1.27)
				)
			)
		)
		(duplicate_pad_numbers_are_jumpers no)
		(fp_line
			(start 0.7874 -0.4064)
			(end 0.7874 0.4064)
			(stroke
				(width 0.1524)
				(type default)
			)
			(layer "F.SilkS")
		)
		(fp_line
			(start -0.7874 -0.4064)
			(end 0.7874 -0.4064)
			(stroke
				(width 0.1524)
				(type default)
			)
			(layer "F.SilkS")
		)
		(fp_line
			(start 0.7874 0.4064)
			(end -0.7874 0.4064)
			(stroke
				(width 0.1524)
				(type default)
			)
			(layer "F.SilkS")
		)
		(fp_line
			(start -0.7874 0.4064)
			(end -0.7874 -0.4064)
			(stroke
				(width 0.1524)
				(type default)
			)
			(layer "F.SilkS")
		)
		(fp_line
			(start -0.12065 -0.305054)
			(end -0.12065 -0.2794)
			(stroke
				(width 0.1)
				(type default)
			)
			(layer "F.Fab")
		)
		(fp_line
			(start -0.67945 -0.305054)
			(end -0.12065 -0.305054)
			(stroke
				(width 0.1)
				(type default)
			)
			(layer "F.Fab")
		)
		(fp_line
			(start 0.67945 -0.3048)
			(end 0.67945 0.3048)
			(stroke
				(width 0.1)
				(type default)
			)
			(layer "F.Fab")
		)
		(fp_line
			(start 0.12065 -0.3048)
			(end 0.67945 -0.3048)
			(stroke
				(width 0.1)
				(type default)
			)
			(layer "F.Fab")
		)
		(fp_line
			(start 0.12065 -0.2794)
			(end 0.12065 -0.3048)
			(stroke
				(width 0.1)
				(type default)
			)
			(layer "F.Fab")
		)
		(fp_line
			(start -0.12065 -0.2794)
			(end 0.12065 -0.2794)
			(stroke
				(width 0.1)
				(type default)
			)
			(layer "F.Fab")
		)
		(fp_line
			(start 0.120396 0.2794)
			(end -0.12065 0.2794)
			(stroke
				(width 0.1)
				(type default)
			)
			(layer "F.Fab")
		)
		(fp_line
			(start -0.12065 0.2794)
			(end -0.12065 0.3048)
			(stroke
				(width 0.1)
				(type default)
			)
			(layer "F.Fab")
		)
		(fp_line
			(start 0.67945 0.3048)
			(end 0.120396 0.3048)
			(stroke
				(width 0.1)
				(type default)
			)
			(layer "F.Fab")
		)
		(fp_line
			(start 0.120396 0.3048)
			(end 0.120396 0.2794)
			(stroke
				(width 0.1)
				(type default)
			)
			(layer "F.Fab")
		)
		(fp_line
			(start -0.12065 0.3048)
			(end -0.67945 0.3048)
			(stroke
				(width 0.1)
				(type default)
			)
			(layer "F.Fab")
		)
		(fp_line
			(start -0.67945 0.3048)
			(end -0.67945 -0.305054)
			(stroke
				(width 0.1)
				(type default)
			)
			(layer "F.Fab")
		)
		(pad "1" smd circle
			(at -0.40005 0 90)
			(size 0 0)
			(layers "F.Cu" "F.Mask" "F.Paste")
			(net "GPU_FPGA_EROT_RECOV_BUF_R_N")
		)
		(pad "2" smd circle
			(at 0.40005 0 90)
			(size 0 0)
			(layers "F.Cu" "F.Mask" "F.Paste")
			(net "GND")
		)
	)
)
